(kicad_pcb
	(version 20260206)
	(generator "pcbnew")
	(generator_version "10.0")
	(general
		(thickness 1.6)
		(legacy_teardrops no)
	)
	(paper "A4")
	(title_block
		(title "Wiwynn_Tioga_Pass_MB.brd")
		(comment 1 "Tioga Pass / footprints 30-36 of 4770")
	)
	(layers
		(0 "F.Cu" signal "TOP")
		(4 "In1.Cu" signal "L2GND")
		(6 "In2.Cu" signal "L3")
		(8 "In3.Cu" signal "L4GND")
		(10 "In4.Cu" signal "L5")
		(12 "In5.Cu" signal "L6GND")
		(14 "In6.Cu" signal "L7VCC")
		(16 "In7.Cu" signal "L8VCC")
		(18 "In8.Cu" signal "L9GND")
		(20 "In9.Cu" signal "L10")
		(22 "In10.Cu" signal "L11GND")
		(24 "In11.Cu" signal "L12")
		(26 "In12.Cu" signal "L13GND")
		(2 "B.Cu" signal "BOTTOM")
		(9 "F.Adhes" user "F.Adhesive")
		(11 "B.Adhes" user "B.Adhesive")
		(13 "F.Paste" user "Package Geometry/Pastemask Top")
		(15 "B.Paste" user "Package Geometry/Pastemask Bottom")
		(5 "F.SilkS" user "Ref Des/Silkscreen Top")
		(7 "B.SilkS" user "Ref Des/Silkscreen Bottom")
		(1 "F.Mask" user "Board Geometry/Soldermask Top")
		(3 "B.Mask" user "Board Geometry/Soldermask Bottom")
		(17 "Dwgs.User" user "User.Drawings")
		(19 "Cmts.User" user "User.Comments")
		(21 "Eco1.User" user "User.Eco1")
		(23 "Eco2.User" user "User.Eco2")
		(25 "Edge.Cuts" user "Board Geometry/Outline")
		(27 "Margin" user)
		(31 "F.CrtYd" user "Package Geometry/Place Bound Top")
		(29 "B.CrtYd" user "Package Geometry/Place Bound Bottom")
		(35 "F.Fab" user "Ref Des/Assembly Top")
		(33 "B.Fab" user "Ref Des/Assembly Bottom")
	)
	(footprint ""
		(layer "F.Cu")
		(at 163.576 -76.708 -90)
		(property "Reference" "R4D28"
			(at 0 0 270)
			(layer "F.SilkS")
			(hide yes)
			(effects
				(font
					(size 1.27 1.27)
				)
			)
		)
		(property "Value" ""
			(at 0 0 270)
			(layer "F.Fab")
			(effects
				(font
					(size 1.27 1.27)
				)
			)
		)
		(duplicate_pad_numbers_are_jumpers no)
		(fp_poly
			(pts
				(xy -0.2794 -0.1016) (xy 0.2794 -0.1016) (xy 0.2794 0.9906) (xy -0.2794 0.9906)
			)
			(stroke
				(width 0)
				(type default)
			)
			(fill no)
			(layer "F.CrtYd")
		)
		(fp_line
			(start -0.2794 0.9906)
			(end 0.2794 0.9906)
			(stroke
				(width 0.1)
				(type default)
			)
			(layer "F.Fab")
		)
		(fp_line
			(start 0.2794 0.9906)
			(end 0.2794 -0.1016)
			(stroke
				(width 0.1)
				(type default)
			)
			(layer "F.Fab")
		)
		(fp_line
			(start -0.2794 -0.1016)
			(end -0.2794 0.9906)
			(stroke
				(width 0.1)
				(type default)
			)
			(layer "F.Fab")
		)
		(fp_line
			(start 0.2794 -0.1016)
			(end -0.2794 -0.1016)
			(stroke
				(width 0.1)
				(type default)
			)
			(layer "F.Fab")
		)
		(pad "1" smd rect
			(at 0 0 270)
			(size 0.508 0.508)
			(layers "F.Cu" "F.Mask" "F.Paste")
			(net "CLK_100M_CPU1_RC_REFCLK1_R_DN")
		)
		(pad "2" smd rect
			(at 0 0.889 270)
			(size 0.508 0.508)
			(layers "F.Cu" "F.Mask" "F.Paste")
			(net "CLK_100M_CPU1_RC_REFCLK1_DN")
		)
		(zone
			(layer "F.Cu")
			(hatch none 0.5)
			(connect_pads
				(clearance 0)
			)
			(min_thickness 0.25)
			(keepout
				(tracks not_allowed)
				(vias allowed)
				(pads allowed)
				(copperpour not_allowed)
				(footprints allowed)
			)
			(placement
				(enabled no)
				(sheetname "")
			)
			(fill
				(thermal_gap 0.5)
				(thermal_bridge_width 0.5)
				(island_removal_mode 0)
			)
			(polygon
				(pts
					(xy 162.941 -76.962) (xy 162.941 -76.454) (xy 163.322 -76.454) (xy 163.322 -76.962)
				)
			)
		)
		(zone
			(layer "F.Cu")
			(hatch none 0.5)
			(connect_pads
				(clearance 0)
			)
			(min_thickness 0.25)
			(keepout
				(tracks allowed)
				(vias not_allowed)
				(pads allowed)
				(copperpour not_allowed)
				(footprints allowed)
			)
			(placement
				(enabled no)
				(sheetname "")
			)
			(fill
				(thermal_gap 0.5)
				(thermal_bridge_width 0.5)
				(island_removal_mode 0)
			)
			(polygon
				(pts
					(xy 163.322 -76.962) (xy 163.322 -76.454) (xy 162.941 -76.454) (xy 162.941 -76.962)
				)
			)
		)
	)
	(footprint ""
		(layer "F.Cu")
		(at 415.671 -23.114)
		(property "Reference" "R1U12"
			(at 0 0 0)
			(layer "F.SilkS")
			(hide yes)
			(effects
				(font
					(size 1.27 1.27)
				)
			)
		)
		(property "Value" ""
			(at 0 0 0)
			(layer "F.Fab")
			(effects
				(font
					(size 1.27 1.27)
				)
			)
		)
		(duplicate_pad_numbers_are_jumpers no)
		(fp_poly
			(pts
				(xy -0.2794 -0.1016) (xy 0.2794 -0.1016) (xy 0.2794 0.9906) (xy -0.2794 0.9906)
			)
			(stroke
				(width 0)
				(type default)
			)
			(fill no)
			(layer "F.CrtYd")
		)
		(fp_line
			(start -0.2794 -0.1016)
			(end -0.2794 0.9906)
			(stroke
				(width 0.1)
				(type default)
			)
			(layer "F.Fab")
		)
		(fp_line
			(start -0.2794 0.9906)
			(end 0.2794 0.9906)
			(stroke
				(width 0.1)
				(type default)
			)
			(layer "F.Fab")
		)
		(fp_line
			(start 0.2794 -0.1016)
			(end -0.2794 -0.1016)
			(stroke
				(width 0.1)
				(type default)
			)
			(layer "F.Fab")
		)
		(fp_line
			(start 0.2794 0.9906)
			(end 0.2794 -0.1016)
			(stroke
				(width 0.1)
				(type default)
			)
			(layer "F.Fab")
		)
		(pad "1" smd rect
			(at 0 0)
			(size 0.508 0.508)
			(layers "F.Cu" "F.Mask" "F.Paste")
			(net "SGPIO_BMC_LD_R_N")
		)
		(pad "2" smd rect
			(at 0 0.889)
			(size 0.508 0.508)
			(layers "F.Cu" "F.Mask" "F.Paste")
			(net "SGPIO_BMC_LD_N")
		)
		(zone
			(layer "F.Cu")
			(hatch none 0.5)
			(connect_pads
				(clearance 0)
			)
			(min_thickness 0.25)
			(keepout
				(tracks allowed)
				(vias not_allowed)
				(pads allowed)
				(copperpour not_allowed)
				(footprints allowed)
			)
			(placement
				(enabled no)
				(sheetname "")
			)
			(fill
				(thermal_gap 0.5)
				(thermal_bridge_width 0.5)
				(island_removal_mode 0)
			)
			(polygon
				(pts
					(xy 415.417 -22.86) (xy 415.925 -22.86) (xy 415.925 -22.479) (xy 415.417 -22.479)
				)
			)
		)
		(zone
			(layer "F.Cu")
			(hatch none 0.5)
			(connect_pads
				(clearance 0)
			)
			(min_thickness 0.25)
			(keepout
				(tracks not_allowed)
				(vias allowed)
				(pads allowed)
				(copperpour not_allowed)
				(footprints allowed)
			)
			(placement
				(enabled no)
				(sheetname "")
			)
			(fill
				(thermal_gap 0.5)
				(thermal_bridge_width 0.5)
				(island_removal_mode 0)
			)
			(polygon
				(pts
					(xy 415.417 -22.479) (xy 415.925 -22.479) (xy 415.925 -22.86) (xy 415.417 -22.86)
				)
			)
		)
	)
	(footprint ""
		(layer "F.Cu")
		(at 477.68002 -12.474194)
		(property "Reference" "R9G22"
			(at -0.8382 -0.67818 0)
			(unlocked yes)
			(layer "F.SilkS")
			(effects
				(font
					(size 0.4064 0.254)
					(thickness 0.1524)
				)
				(justify left)
			)
		)
		(property "Value" ""
			(at 0 0 0)
			(layer "F.Fab")
			(effects
				(font
					(size 1.27 1.27)
				)
			)
		)
		(duplicate_pad_numbers_are_jumpers no)
		(fp_poly
			(pts
				(xy -0.2794 -0.1016) (xy 0.2794 -0.1016) (xy 0.2794 0.9906) (xy -0.2794 0.9906)
			)
			(stroke
				(width 0)
				(type default)
			)
			(fill no)
			(layer "F.CrtYd")
		)
		(fp_line
			(start -0.2794 -0.1016)
			(end -0.2794 0.9906)
			(stroke
				(width 0.1)
				(type default)
			)
			(layer "F.Fab")
		)
		(fp_line
			(start -0.2794 0.9906)
			(end 0.2794 0.9906)
			(stroke
				(width 0.1)
				(type default)
			)
			(layer "F.Fab")
		)
		(fp_line
			(start 0.2794 -0.1016)
			(end -0.2794 -0.1016)
			(stroke
				(width 0.1)
				(type default)
			)
			(layer "F.Fab")
		)
		(fp_line
			(start 0.2794 0.9906)
			(end 0.2794 -0.1016)
			(stroke
				(width 0.1)
				(type default)
			)
			(layer "F.Fab")
		)
		(pad "1" smd rect
			(at 0 0)
			(size 0.508 0.508)
			(layers "F.Cu" "F.Mask" "F.Paste")
			(net "NIC_MDI_SPRV_RJ45_0_DN")
		)
		(pad "2" smd rect
			(at 0 0.889)
			(size 0.508 0.508)
			(layers "F.Cu" "F.Mask" "F.Paste")
			(net "NIC_MDI_SPRV_RJ45_0_R_DN")
		)
		(zone
			(layer "F.Cu")
			(hatch none 0.5)
			(connect_pads
				(clearance 0)
			)
			(min_thickness 0.25)
			(keepout
				(tracks allowed)
				(vias not_allowed)
				(pads allowed)
				(copperpour not_allowed)
				(footprints allowed)
			)
			(placement
				(enabled no)
				(sheetname "")
			)
			(fill
				(thermal_gap 0.5)
				(thermal_bridge_width 0.5)
				(island_removal_mode 0)
			)
			(polygon
				(pts
					(xy 477.42602 -12.220194) (xy 477.93402 -12.220194) (xy 477.93402 -11.839194) (xy 477.42602 -11.839194)
				)
			)
		)
		(zone
			(layer "F.Cu")
			(hatch none 0.5)
			(connect_pads
				(clearance 0)
			)
			(min_thickness 0.25)
			(keepout
				(tracks not_allowed)
				(vias allowed)
				(pads allowed)
				(copperpour not_allowed)
				(footprints allowed)
			)
			(placement
				(enabled no)
				(sheetname "")
			)
			(fill
				(thermal_gap 0.5)
				(thermal_bridge_width 0.5)
				(island_removal_mode 0)
			)
			(polygon
				(pts
					(xy 477.42602 -11.839194) (xy 477.93402 -11.839194) (xy 477.93402 -12.220194) (xy 477.42602 -12.220194)
				)
			)
		)
	)
	(footprint ""
		(layer "F.Cu")
		(at 104.5591 -12.954 90)
		(property "Reference" "C2G6"
			(at 1.848866 0.752348 90)
			(unlocked yes)
			(layer "F.SilkS")
			(effects
				(font
					(size 1.27 0.9652)
					(thickness 0.1524)
				)
			)
		)
		(property "Value" ""
			(at 0 0 90)
			(layer "F.Fab")
			(effects
				(font
					(size 1.27 1.27)
				)
			)
		)
		(duplicate_pad_numbers_are_jumpers no)
		(fp_rect
			(start -0.500126 1.598422)
			(end 0.500126 -0.201422)
			(stroke
				(width 0)
				(type default)
			)
			(fill no)
			(layer "F.CrtYd")
		)
		(fp_line
			(start 0.500126 -0.201422)
			(end 0.500126 1.598422)
			(stroke
				(width 0.1)
				(type default)
			)
			(layer "F.Fab")
		)
		(fp_line
			(start -0.500126 -0.201422)
			(end 0.500126 -0.201422)
			(stroke
				(width 0.1)
				(type default)
			)
			(layer "F.Fab")
		)
		(fp_line
			(start 0.500126 1.598422)
			(end -0.500126 1.598422)
			(stroke
				(width 0.1)
				(type default)
			)
			(layer "F.Fab")
		)
		(fp_line
			(start -0.500126 1.598422)
			(end -0.500126 -0.201422)
			(stroke
				(width 0.1)
				(type default)
			)
			(layer "F.Fab")
		)
		(pad "1" smd rect
			(at 0 0)
			(size 0.889 0.9906)
			(layers "F.Cu" "F.Mask" "F.Paste")
			(net "PVDDQ_GHJ")
		)
		(pad "2" smd rect
			(at 0 1.397)
			(size 0.889 0.9906)
			(layers "F.Cu" "F.Mask" "F.Paste")
			(net "GND")
		)
		(zone
			(layer "F.Cu")
			(hatch none 0.5)
			(connect_pads
				(clearance 0)
			)
			(min_thickness 0.25)
			(keepout
				(tracks allowed)
				(vias not_allowed)
				(pads allowed)
				(copperpour not_allowed)
				(footprints allowed)
			)
			(placement
				(enabled no)
				(sheetname "")
			)
			(fill
				(thermal_gap 0.5)
				(thermal_bridge_width 0.5)
				(island_removal_mode 0)
			)
			(polygon
				(pts
					(xy 105.5116 -12.4587) (xy 105.5116 -13.4493) (xy 105.0036 -13.4493) (xy 105.0036 -12.4587)
				)
			)
		)
		(zone
			(layer "F.Cu")
			(hatch none 0.5)
			(connect_pads
				(clearance 0)
			)
			(min_thickness 0.25)
			(keepout
				(tracks not_allowed)
				(vias allowed)
				(pads allowed)
				(copperpour not_allowed)
				(footprints allowed)
			)
			(placement
				(enabled no)
				(sheetname "")
			)
			(fill
				(thermal_gap 0.5)
				(thermal_bridge_width 0.5)
				(island_removal_mode 0)
			)
			(polygon
				(pts
					(xy 105.5116 -12.4587) (xy 105.5116 -13.4493) (xy 105.0036 -13.4493) (xy 105.0036 -12.4587)
				)
			)
		)
	)
	(footprint ""
		(layer "F.Cu")
		(at 346.9894 -19.304 180)
		(property "Reference" "C7F15"
			(at 0 0 180)
			(layer "F.SilkS")
			(hide yes)
			(effects
				(font
					(size 1.27 1.27)
				)
			)
		)
		(property "Value" ""
			(at 0 0 180)
			(layer "F.Fab")
			(effects
				(font
					(size 1.27 1.27)
				)
			)
		)
		(duplicate_pad_numbers_are_jumpers no)
		(fp_rect
			(start 0.3048 -0.1016)
			(end -0.3048 0.9906)
			(stroke
				(width 0)
				(type default)
			)
			(fill no)
			(layer "F.CrtYd")
		)
		(fp_line
			(start 0.3048 0.9906)
			(end 0.3048 -0.1016)
			(stroke
				(width 0.1)
				(type default)
			)
			(layer "F.Fab")
		)
		(fp_line
			(start 0.3048 -0.1016)
			(end -0.3048 -0.1016)
			(stroke
				(width 0.1)
				(type default)
			)
			(layer "F.Fab")
		)
		(fp_line
			(start -0.3048 0.9906)
			(end 0.3048 0.9906)
			(stroke
				(width 0.1)
				(type default)
			)
			(layer "F.Fab")
		)
		(fp_line
			(start -0.3048 -0.1016)
			(end -0.3048 0.9906)
			(stroke
				(width 0.1)
				(type default)
			)
			(layer "F.Fab")
		)
		(pad "1" smd rect
			(at 0 0 180)
			(size 0.508 0.508)
			(layers "F.Cu" "F.Mask" "F.Paste")
			(net "VR_PVDDQ_ABC_VD12")
		)
		(pad "2" smd rect
			(at 0 0.889 180)
			(size 0.508 0.508)
			(layers "F.Cu" "F.Mask" "F.Paste")
			(net "GND")
		)
		(zone
			(layer "F.Cu")
			(hatch none 0.5)
			(connect_pads
				(clearance 0)
			)
			(min_thickness 0.25)
			(keepout
				(tracks allowed)
				(vias not_allowed)
				(pads allowed)
				(copperpour not_allowed)
				(footprints allowed)
			)
			(placement
				(enabled no)
				(sheetname "")
			)
			(fill
				(thermal_gap 0.5)
				(thermal_bridge_width 0.5)
				(island_removal_mode 0)
			)
			(polygon
				(pts
					(xy 346.7354 -19.558) (xy 347.2434 -19.558) (xy 347.2434 -19.939) (xy 346.7354 -19.939)
				)
			)
		)
		(zone
			(layer "F.Cu")
			(hatch none 0.5)
			(connect_pads
				(clearance 0)
			)
			(min_thickness 0.25)
			(keepout
				(tracks not_allowed)
				(vias allowed)
				(pads allowed)
				(copperpour not_allowed)
				(footprints allowed)
			)
			(placement
				(enabled no)
				(sheetname "")
			)
			(fill
				(thermal_gap 0.5)
				(thermal_bridge_width 0.5)
				(island_removal_mode 0)
			)
			(polygon
				(pts
					(xy 346.7354 -19.558) (xy 347.2434 -19.558) (xy 347.2434 -19.939) (xy 346.7354 -19.939)
				)
			)
		)
	)
	(footprint ""
		(layer "F.Cu")
		(at 216.911936 11.952478 -90)
		(property "Reference" "T1P4"
			(at 0 0 270)
			(layer "F.SilkS")
			(hide yes)
			(effects
				(font
					(size 1.27 1.27)
				)
			)
		)
		(property "Value" "*"
			(at -3.302 1.12395 270)
			(unlocked yes)
			(layer "F.Fab")
			(hide yes)
			(effects
				(font
					(size 0.889 0.889)
					(thickness 0.1524)
				)
			)
		)
		(property "Device Type" "TPAD-DIFF-4P-GP_DISCRET-GB3-TPA"
			(at -3.302 -0.40005 270)
			(unlocked yes)
			(layer "F.Fab")
			(hide yes)
			(effects
				(font
					(size 0.889 0.889)
					(thickness 0.1524)
				)
			)
		)
		(duplicate_pad_numbers_are_jumpers no)
		(fp_line
			(start -2.286 2.286)
			(end 2.286 2.286)
			(stroke
				(width 0.1524)
				(type default)
			)
			(layer "F.SilkS")
		)
		(fp_line
			(start 2.286 2.286)
			(end 2.286 -2.286)
			(stroke
				(width 0.1524)
				(type default)
			)
			(layer "F.SilkS")
		)
		(fp_line
			(start -2.286 -2.286)
			(end -2.286 2.286)
			(stroke
				(width 0.1524)
				(type default)
			)
			(layer "F.SilkS")
		)
		(fp_line
			(start 2.286 -2.286)
			(end -2.286 -2.286)
			(stroke
				(width 0.1524)
				(type default)
			)
			(layer "F.SilkS")
		)
		(fp_line
			(start -2.413 -2.413)
			(end -2.413 -1.143)
			(stroke
				(width 0.4064)
				(type default)
			)
			(layer "F.SilkS")
		)
		(fp_line
			(start -1.143 -2.413)
			(end -2.413 -2.413)
			(stroke
				(width 0.4064)
				(type default)
			)
			(layer "F.SilkS")
		)
		(fp_rect
			(start -2.54 2.54)
			(end 2.54 -2.54)
			(stroke
				(width 0)
				(type default)
			)
			(fill no)
			(layer "F.CrtYd")
		)
		(fp_rect
			(start -2.54 2.54)
			(end 2.54 -2.54)
			(stroke
				(width 0)
				(type default)
			)
			(fill no)
			(layer "F.Fab")
		)
		(pad "1" thru_hole circle
			(at -1.27 -1.27 270)
			(size 1.524 1.524)
			(drill 0.9144)
			(layers "*.Cu" "*.Mask")
			(remove_unused_layers no)
			(net "L10_85OHM_6INCH_DP")
			(clearance -0.0508)
			(thermal_gap 0.127)
			(padstack
				(mode front_inner_back)
				(layer "Inner"
					(shape circle)
					(size 1.1684 1.1684)
					(clearance 0.127)
				)
				(layer "B.Cu"
					(shape circle)
					(size 1.524 1.524)
					(clearance -0.0508)
				)
			)
		)
		(pad "2" thru_hole circle
			(at 1.27 -1.27 270)
			(size 1.524 1.524)
			(drill 0.9144)
			(layers "*.Cu" "*.Mask")
			(remove_unused_layers no)
			(net "L10_85OHM_6INCH_DN")
			(clearance -0.0508)
			(thermal_gap 0.127)
			(padstack
				(mode front_inner_back)
				(layer "Inner"
					(shape circle)
					(size 1.1684 1.1684)
					(clearance 0.127)
				)
				(layer "B.Cu"
					(shape circle)
					(size 1.524 1.524)
					(clearance -0.0508)
				)
			)
		)
		(pad "GND1" thru_hole rect
			(at -1.27 1.27 270)
			(size 1.524 1.524)
			(drill 0.9144)
			(layers "*.Cu" "*.Mask")
			(remove_unused_layers no)
			(net "GND")
			(clearance -0.0508)
			(thermal_gap 0.127)
			(padstack
				(mode front_inner_back)
				(layer "Inner"
					(shape circle)
					(size 1.1684 1.1684)
					(clearance 0.127)
				)
				(layer "B.Cu"
					(shape rect)
					(size 1.524 1.524)
					(clearance -0.0508)
				)
			)
		)
		(pad "GND2" thru_hole rect
			(at 1.27 1.27 270)
			(size 1.524 1.524)
			(drill 0.9144)
			(layers "*.Cu" "*.Mask")
			(remove_unused_layers no)
			(net "GND")
			(clearance -0.0508)
			(thermal_gap 0.127)
			(padstack
				(mode front_inner_back)
				(layer "Inner"
					(shape circle)
					(size 1.1684 1.1684)
					(clearance 0.127)
				)
				(layer "B.Cu"
					(shape rect)
					(size 1.524 1.524)
					(clearance -0.0508)
				)
			)
		)
	)
	(footprint ""
		(layer "F.Cu")
		(at 369.477544 -10.916158)
		(property "Reference" "C7G11"
			(at 0 0 0)
			(layer "F.SilkS")
			(hide yes)
			(effects
				(font
					(size 1.27 1.27)
				)
			)
		)
		(property "Value" ""
			(at 0 0 0)
			(layer "F.Fab")
			(effects
				(font
					(size 1.27 1.27)
				)
			)
		)
		(duplicate_pad_numbers_are_jumpers no)
		(fp_rect
			(start -0.3048 0.9906)
			(end 0.3048 -0.1016)
			(stroke
				(width 0)
				(type default)
			)
			(fill no)
			(layer "F.CrtYd")
		)
		(fp_line
			(start -0.3048 -0.1016)
			(end -0.3048 0.9906)
			(stroke
				(width 0.1)
				(type default)
			)
			(layer "F.Fab")
		)
		(fp_line
			(start -0.3048 0.9906)
			(end 0.3048 0.9906)
			(stroke
				(width 0.1)
				(type default)
			)
			(layer "F.Fab")
		)
		(fp_line
			(start 0.3048 -0.1016)
			(end -0.3048 -0.1016)
			(stroke
				(width 0.1)
				(type default)
			)
			(layer "F.Fab")
		)
		(fp_line
			(start 0.3048 0.9906)
			(end 0.3048 -0.1016)
			(stroke
				(width 0.1)
				(type default)
			)
			(layer "F.Fab")
		)
		(pad "1" smd rect
			(at 0 0)
			(size 0.508 0.508)
			(layers "F.Cu" "F.Mask" "F.Paste")
			(net "P3E_CPU0_PE2_SS_TXP<12>")
		)
		(pad "2" smd rect
			(at 0 0.889)
			(size 0.508 0.508)
			(layers "F.Cu" "F.Mask" "F.Paste")
			(net "P3E_CPU0_PE2_SS_C_TXP<12>")
		)
		(zone
			(layer "F.Cu")
			(hatch none 0.5)
			(connect_pads
				(clearance 0)
			)
			(min_thickness 0.25)
			(keepout
				(tracks allowed)
				(vias not_allowed)
				(pads allowed)
				(copperpour not_allowed)
				(footprints allowed)
			)
			(placement
				(enabled no)
				(sheetname "")
			)
			(fill
				(thermal_gap 0.5)
				(thermal_bridge_width 0.5)
				(island_removal_mode 0)
			)
			(polygon
				(pts
					(xy 369.223544 -10.281158) (xy 369.731544 -10.281158) (xy 369.731544 -10.662158) (xy 369.223544 -10.662158)
				)
			)
		)
		(zone
			(layer "F.Cu")
			(hatch none 0.5)
			(connect_pads
				(clearance 0)
			)
			(min_thickness 0.25)
			(keepout
				(tracks not_allowed)
				(vias allowed)
				(pads allowed)
				(copperpour not_allowed)
				(footprints allowed)
			)
			(placement
				(enabled no)
				(sheetname "")
			)
			(fill
				(thermal_gap 0.5)
				(thermal_bridge_width 0.5)
				(island_removal_mode 0)
			)
			(polygon
				(pts
					(xy 369.223544 -10.281158) (xy 369.731544 -10.281158) (xy 369.731544 -10.662158) (xy 369.223544 -10.662158)
				)
			)
		)
	)
)
